# S9S_MB_2U (Grand Teton) — schematic netlist excerpt (pin names and nets, part order shuffled) for the footprints in the layout excerpt that follows; sources: Cadence DE-HDL packaged netlist, KiCad conversion of 03242023_DA0F0TMBIJ0_F0T_Motherboard_J_brd_V01_OCP.brd

C2014  Q_CAP  0.1UF 25V 10% X7R  pkg 0402  page 172 : A = P3V3_AUX ; B = GND
C1619  Q_CAP  0.1UF 25V 10% X7R  pkg 0402  page 224 : A = P3V3_AUX ; B = GND

(kicad_pcb
	(version 20260206)
	(generator "pcbnew")
	(generator_version "10.0")
	(general
		(thickness 1.6)
		(legacy_teardrops no)
	)
	(paper "A4")
	(title_block
		(title "03242023_DA0F0TMBIJ0_F0T_Motherboard_J_brd_V01_OCP.brd")
		(comment 1 "Grand Teton / footprints 134-135 of 6105")
	)
	(layers
		(0 "F.Cu" signal "TOP")
		(4 "In1.Cu" signal "GND")
		(6 "In2.Cu" signal "IN1")
		(8 "In3.Cu" signal "GND1")
		(10 "In4.Cu" signal "IN2")
		(12 "In5.Cu" signal "GND2")
		(14 "In6.Cu" signal "IN3")
		(16 "In7.Cu" signal "GND3")
		(18 "In8.Cu" signal "VCC")
		(20 "In9.Cu" signal "VCC1")
		(22 "In10.Cu" signal "GND4")
		(24 "In11.Cu" signal "IN4")
		(26 "In12.Cu" signal "GND5")
		(28 "In13.Cu" signal "IN5")
		(30 "In14.Cu" signal "GND6")
		(32 "In15.Cu" signal "IN6")
		(34 "In16.Cu" signal "GND7")
		(2 "B.Cu" signal "BOTTOM")
		(9 "F.Adhes" user "F.Adhesive")
		(11 "B.Adhes" user "B.Adhesive")
		(13 "F.Paste" user "Package Geometry/Pastemask Top")
		(15 "B.Paste" user "Package Geometry/Pastemask Bottom")
		(5 "F.SilkS" user "Ref Des/Silkscreen Top")
		(7 "B.SilkS" user "Ref Des/Silkscreen Bottom")
		(1 "F.Mask" user "Board Geometry/Soldermask Top")
		(3 "B.Mask" user "Board Geometry/Soldermask Bottom")
		(17 "Dwgs.User" user "User.Drawings")
		(19 "Cmts.User" user "User.Comments")
		(21 "Eco1.User" user "User.Eco1")
		(23 "Eco2.User" user "User.Eco2")
		(25 "Edge.Cuts" user "Board Geometry/Outline")
		(27 "Margin" user)
		(31 "F.CrtYd" user "Package Geometry/Place Bound Top")
		(29 "B.CrtYd" user "Package Geometry/Place Bound Bottom")
		(35 "F.Fab" user "Ref Des/Assembly Top")
		(33 "B.Fab" user "Ref Des/Assembly Bottom")
	)
	(footprint ""
		(layer "F.Cu")
		(at 144.320006 -77.532738)
		(property "Reference" "C1619"
			(at 0 0 0)
			(layer "F.SilkS")
			(hide yes)
			(effects
				(font
					(size 1.27 1.27)
				)
			)
		)
		(property "Value" ""
			(at 0 0 0)
			(layer "F.Fab")
			(effects
				(font
					(size 1.27 1.27)
				)
			)
		)
		(duplicate_pad_numbers_are_jumpers no)
		(fp_line
			(start -0.7874 -0.4064)
			(end 0.7874 -0.4064)
			(stroke
				(width 0.1524)
				(type default)
			)
			(layer "F.SilkS")
		)
		(fp_line
			(start -0.7874 0.4064)
			(end -0.7874 -0.4064)
			(stroke
				(width 0.1524)
				(type default)
			)
			(layer "F.SilkS")
		)
		(fp_line
			(start 0.7874 -0.4064)
			(end 0.7874 0.4064)
			(stroke
				(width 0.1524)
				(type default)
			)
			(layer "F.SilkS")
		)
		(fp_line
			(start 0.7874 0.4064)
			(end -0.7874 0.4064)
			(stroke
				(width 0.1524)
				(type default)
			)
			(layer "F.SilkS")
		)
		(fp_line
			(start -0.67945 -0.305054)
			(end -0.12065 -0.305054)
			(stroke
				(width 0.1)
				(type default)
			)
			(layer "F.Fab")
		)
		(fp_line
			(start -0.67945 0.3048)
			(end -0.67945 -0.305054)
			(stroke
				(width 0.1)
				(type default)
			)
			(layer "F.Fab")
		)
		(fp_line
			(start -0.12065 -0.305054)
			(end -0.12065 -0.2794)
			(stroke
				(width 0.1)
				(type default)
			)
			(layer "F.Fab")
		)
		(fp_line
			(start -0.12065 -0.2794)
			(end 0.12065 -0.2794)
			(stroke
				(width 0.1)
				(type default)
			)
			(layer "F.Fab")
		)
		(fp_line
			(start -0.12065 0.2794)
			(end -0.12065 0.3048)
			(stroke
				(width 0.1)
				(type default)
			)
			(layer "F.Fab")
		)
		(fp_line
			(start -0.12065 0.3048)
			(end -0.67945 0.3048)
			(stroke
				(width 0.1)
				(type default)
			)
			(layer "F.Fab")
		)
		(fp_line
			(start 0.120396 0.2794)
			(end -0.12065 0.2794)
			(stroke
				(width 0.1)
				(type default)
			)
			(layer "F.Fab")
		)
		(fp_line
			(start 0.120396 0.3048)
			(end 0.120396 0.2794)
			(stroke
				(width 0.1)
				(type default)
			)
			(layer "F.Fab")
		)
		(fp_line
			(start 0.12065 -0.3048)
			(end 0.67945 -0.3048)
			(stroke
				(width 0.1)
				(type default)
			)
			(layer "F.Fab")
		)
		(fp_line
			(start 0.12065 -0.2794)
			(end 0.12065 -0.3048)
			(stroke
				(width 0.1)
				(type default)
			)
			(layer "F.Fab")
		)
		(fp_line
			(start 0.67945 -0.3048)
			(end 0.67945 0.3048)
			(stroke
				(width 0.1)
				(type default)
			)
			(layer "F.Fab")
		)
		(fp_line
			(start 0.67945 0.3048)
			(end 0.120396 0.3048)
			(stroke
				(width 0.1)
				(type default)
			)
			(layer "F.Fab")
		)
		(pad "1" smd circle
			(at -0.40005 0)
			(size 0 0)
			(layers "F.Cu" "F.Mask" "F.Paste")
			(net "P3V3_AUX")
		)
		(pad "2" smd circle
			(at 0.40005 0)
			(size 0 0)
			(layers "F.Cu" "F.Mask" "F.Paste")
			(net "GND")
		)
	)
	(footprint ""
		(layer "F.Cu")
		(at 209.959956 -37.769292 90)
		(property "Reference" "C2014"
			(at 0 0 90)
			(layer "F.SilkS")
			(hide yes)
			(effects
				(font
					(size 1.27 1.27)
				)
			)
		)
		(property "Value" ""
			(at 0 0 90)
			(layer "F.Fab")
			(effects
				(font
					(size 1.27 1.27)
				)
			)
		)
		(duplicate_pad_numbers_are_jumpers no)
		(fp_line
			(start 0.7874 -0.4064)
			(end 0.7874 0.4064)
			(stroke
				(width 0.1524)
				(type default)
			)
			(layer "F.SilkS")
		)
		(fp_line
			(start -0.7874 -0.4064)
			(end 0.7874 -0.4064)
			(stroke
				(width 0.1524)
				(type default)
			)
			(layer "F.SilkS")
		)
		(fp_line
			(start 0.7874 0.4064)
			(end -0.7874 0.4064)
			(stroke
				(width 0.1524)
				(type default)
			)
			(layer "F.SilkS")
		)
		(fp_line
			(start -0.7874 0.4064)
			(end -0.7874 -0.4064)
			(stroke
				(width 0.1524)
				(type default)
			)
			(layer "F.SilkS")
		)
		(fp_line
			(start -0.12065 -0.305054)
			(end -0.12065 -0.2794)
			(stroke
				(width 0.1)
				(type default)
			)
			(layer "F.Fab")
		)
		(fp_line
			(start -0.67945 -0.305054)
			(end -0.12065 -0.305054)
			(stroke
				(width 0.1)
				(type default)
			)
			(layer "F.Fab")
		)
		(fp_line
			(start 0.67945 -0.3048)
			(end 0.67945 0.3048)
			(stroke
				(width 0.1)
				(type default)
			)
			(layer "F.Fab")
		)
		(fp_line
			(start 0.12065 -0.3048)
			(end 0.67945 -0.3048)
			(stroke
				(width 0.1)
				(type default)
			)
			(layer "F.Fab")
		)
		(fp_line
			(start 0.12065 -0.2794)
			(end 0.12065 -0.3048)
			(stroke
				(width 0.1)
				(type default)
			)
			(layer "F.Fab")
		)
		(fp_line
			(start -0.12065 -0.2794)
			(end 0.12065 -0.2794)
			(stroke
				(width 0.1)
				(type default)
			)
			(layer "F.Fab")
		)
		(fp_line
			(start 0.120396 0.2794)
			(end -0.12065 0.2794)
			(stroke
				(width 0.1)
				(type default)
			)
			(layer "F.Fab")
		)
		(fp_line
			(start -0.12065 0.2794)
			(end -0.12065 0.3048)
			(stroke
				(width 0.1)
				(type default)
			)
			(layer "F.Fab")
		)
		(fp_line
			(start 0.67945 0.3048)
			(end 0.120396 0.3048)
			(stroke
				(width 0.1)
				(type default)
			)
			(layer "F.Fab")
		)
		(fp_line
			(start 0.120396 0.3048)
			(end 0.120396 0.2794)
			(stroke
				(width 0.1)
				(type default)
			)
			(layer "F.Fab")
		)
		(fp_line
			(start -0.12065 0.3048)
			(end -0.67945 0.3048)
			(stroke
				(width 0.1)
				(type default)
			)
			(layer "F.Fab")
		)
		(fp_line
			(start -0.67945 0.3048)
			(end -0.67945 -0.305054)
			(stroke
				(width 0.1)
				(type default)
			)
			(layer "F.Fab")
		)
		(pad "1" smd circle
			(at -0.40005 0 90)
			(size 0 0)
			(layers "F.Cu" "F.Mask" "F.Paste")
			(net "P3V3_AUX")
		)
		(pad "2" smd circle
			(at 0.40005 0 90)
			(size 0 0)
			(layers "F.Cu" "F.Mask" "F.Paste")
			(net "GND")
		)
	)
)
